FILE_TYPE = CONNECTIVITY;
{Allegro Design Entry HDL 17.2-2016 S081 (4005846) 1/11/2022}
"PAGE_NUMBER" = 101;
0"NC";
1"M_E_CPU1_SA_CB<7:0>";
2"M_E_CPU1_SA_CA<6:0>";
3"M_E_CPU1_SB_CA<6:0>";
4"M_E_CPU1_SB_CB<7:0>";
5"M_E_CPU1_SA_DQ<31:0>";
6"M_E_CPU1_SB_DQ<31:0>";
7"M_E_CPU1_SA_DQS_DN<9:0>";
8"M_E_CPU1_SA_DQS_DP<9:0>";
9"M_E_CPU1_SB_DQS_DN<9:0>";
10"M_E_CPU1_SB_DQS_DP<9:0>";
11"GND\g";
12"GND\g";
13"P3V3_STBY\g";
14"P3V3_STBY\g";
15"I3C_SPD_DDRAF_CPU1_SDA";
16"I3C_SPD_DDRE_CPU1_SCL";
17"I3C_SPD_DDRAF_CPU1_SCL";
18"PWRGD_CHE_CPU1_DIMM";
19"TP_CHE_CPU1_DIMM_RFU_6";
20"PD_CHE_CPU1_DIMM_SAA";
21"M_E_CPU1_ALERT_N";
22"M_E_CPU1_RESET_N";
23"M_E_CPU1_SA_RSP<0>";
24"PWRGD_CHAF_CPU1";
25"P12V_MEM_2\g";
26"GND\g";
27"GND\g";
28"GND\g";
29"M_E_CPU1_SB_DQS_DP<9>";
30"M_E_CPU1_SB_DQS_DN<9>";
31"M_E_CPU1_SA_DQS_DP<9>";
32"M_E_CPU1_SA_DQS_DN<9>";
33"M_E_CPU1_SA_DQS_DP<8>";
34"M_E_CPU1_SA_DQS_DN<8>";
35"M_E_CPU1_SB_DQS_DN<7>";
36"M_E_CPU1_SA_DQS_DP<7>";
37"M_E_CPU1_SB_DQS_DP<6>";
38"M_E_CPU1_SB_DQS_DN<6>";
39"M_E_CPU1_SA_DQS_DN<6>";
40"M_E_CPU1_SB_DQS_DP<5>";
41"M_E_CPU1_SB_DQS_DN<5>";
42"M_E_CPU1_SA_DQS_DP<5>";
43"M_E_CPU1_SA_DQS_DN<5>";
44"M_E_CPU1_SB_DQS_DP<4>";
45"M_E_CPU1_SB_DQS_DN<4>";
46"M_E_CPU1_SA_DQS_DP<4>";
47"M_E_CPU1_SA_DQS_DN<4>";
48"M_E_CPU1_SB_DQS_DP<3>";
49"M_E_CPU1_SB_DQS_DN<3>";
50"M_E_CPU1_SA_DQS_DP<3>";
51"M_E_CPU1_SA_DQS_DN<3>";
52"M_E_CPU1_SB_DQS_DP<2>";
53"M_E_CPU1_SB_DQS_DN<2>";
54"M_E_CPU1_SA_DQS_DP<2>";
55"M_E_CPU1_SA_DQS_DN<2>";
56"M_E_CPU1_SB_DQS_DP<1>";
57"M_E_CPU1_SB_DQS_DN<1>";
58"M_E_CPU1_SA_DQS_DP<1>";
59"M_E_CPU1_SA_DQS_DN<1>";
60"M_E_CPU1_SB_DQS_DP<0>";
61"M_E_CPU1_SB_DQS_DN<0>";
62"M_E_CPU1_SA_DQS_DP<0>";
63"M_E_CPU1_SA_DQS_DN<0>";
64"M_E_CPU1_SB_DQS_DP<7>";
65"M_E_CPU1_SB_DQS_DN<8>";
66"M_E_CPU1_SB_DQS_DP<8>";
67"M_E_CPU1_SA_DQS_DP<6>";
68"M_E_CPU1_SA_DQS_DN<7>";
69"TP_CHE_CPU1_DIMM_RFU_0";
70"TP_CHE_CPU1_DIMM_RFU_1";
71"TP_CHE_CPU1_DIMM_RFU_2";
72"TP_CHE_CPU1_DIMM_RFU_3";
73"TP_CHE_CPU1_DIMM_RFU_4";
74"TP_CHE_CPU1_DIMM_RFU_5";
75"M_E_CPU1_SB_PAR";
76"M_E_CPU1_SA_PAR";
77"M_E_CPU1_SB_RSP<0>";
78"M_E_CPU1_SB_DQ<0>";
79"M_E_CPU1_SB_DQ<1>";
80"M_E_CPU1_SB_DQ<2>";
81"M_E_CPU1_SB_DQ<3>";
82"M_E_CPU1_SB_DQ<4>";
83"M_E_CPU1_SB_DQ<5>";
84"M_E_CPU1_SB_DQ<6>";
85"M_E_CPU1_SB_DQ<7>";
86"M_E_CPU1_SB_DQ<8>";
87"M_E_CPU1_SB_DQ<9>";
88"M_E_CPU1_SB_DQ<10>";
89"M_E_CPU1_SB_DQ<11>";
90"M_E_CPU1_SB_DQ<12>";
91"M_E_CPU1_SB_DQ<13>";
92"M_E_CPU1_SB_DQ<14>";
93"M_E_CPU1_SB_DQ<15>";
94"M_E_CPU1_SB_DQ<16>";
95"M_E_CPU1_SB_DQ<17>";
96"M_E_CPU1_SB_DQ<18>";
97"M_E_CPU1_SB_DQ<19>";
98"M_E_CPU1_SB_DQ<20>";
99"M_E_CPU1_SB_DQ<21>";
100"M_E_CPU1_SB_DQ<22>";
101"M_E_CPU1_SB_DQ<23>";
102"M_E_CPU1_SB_DQ<24>";
103"M_E_CPU1_SB_DQ<25>";
104"M_E_CPU1_SB_DQ<26>";
105"M_E_CPU1_SB_DQ<27>";
106"M_E_CPU1_SB_DQ<28>";
107"M_E_CPU1_SB_DQ<29>";
108"M_E_CPU1_SB_DQ<30>";
109"M_E_CPU1_SB_DQ<31>";
110"M_E_CPU1_SA_DQ<0>";
111"M_E_CPU1_SA_DQ<1>";
112"M_E_CPU1_SA_DQ<2>";
113"M_E_CPU1_SA_DQ<3>";
114"M_E_CPU1_SA_DQ<4>";
115"M_E_CPU1_SA_DQ<5>";
116"M_E_CPU1_SA_DQ<6>";
117"M_E_CPU1_SA_DQ<7>";
118"M_E_CPU1_SA_DQ<8>";
119"M_E_CPU1_SA_DQ<9>";
120"M_E_CPU1_SA_DQ<10>";
121"M_E_CPU1_SA_DQ<11>";
122"M_E_CPU1_SA_DQ<12>";
123"M_E_CPU1_SA_DQ<13>";
124"M_E_CPU1_SA_DQ<14>";
125"M_E_CPU1_SA_DQ<15>";
126"M_E_CPU1_SA_DQ<16>";
127"M_E_CPU1_SA_DQ<17>";
128"M_E_CPU1_SA_DQ<18>";
129"M_E_CPU1_SA_DQ<19>";
130"M_E_CPU1_SA_DQ<20>";
131"M_E_CPU1_SA_DQ<21>";
132"M_E_CPU1_SA_DQ<22>";
133"M_E_CPU1_SA_DQ<23>";
134"M_E_CPU1_SA_DQ<24>";
135"M_E_CPU1_SA_DQ<25>";
136"M_E_CPU1_SA_DQ<26>";
137"M_E_CPU1_SA_DQ<27>";
138"M_E_CPU1_SA_DQ<28>";
139"M_E_CPU1_SA_DQ<29>";
140"M_E_CPU1_SA_DQ<30>";
141"M_E_CPU1_SB_CS_N<1>";
142"M_E_CPU1_SA_CS_N<1>";
143"M_E_CPU1_SB_CS_N<0>";
144"M_E_CPU1_SA_CS_N<0>";
145"M_E_CPU1_CLK_DP<0>";
146"M_E_CPU1_CLK_DN<0>";
147"M_E_CPU1_SB_CB<0>";
148"M_E_CPU1_SB_CB<1>";
149"M_E_CPU1_SB_CB<2>";
150"M_E_CPU1_SB_CB<3>";
151"M_E_CPU1_SB_CB<4>";
152"M_E_CPU1_SB_CB<5>";
153"M_E_CPU1_SB_CB<6>";
154"M_E_CPU1_SA_CB<0>";
155"M_E_CPU1_SA_CB<2>";
156"M_E_CPU1_SA_CB<3>";
157"M_E_CPU1_SA_CB<5>";
158"M_E_CPU1_SA_CB<6>";
159"M_E_CPU1_SB_CA<6>";
160"M_E_CPU1_SA_CA<6>";
161"M_E_CPU1_SB_CA<5>";
162"M_E_CPU1_SA_CA<5>";
163"M_E_CPU1_SB_CA<4>";
164"M_E_CPU1_SA_CA<4>";
165"M_E_CPU1_SB_CA<3>";
166"M_E_CPU1_SA_CA<3>";
167"M_E_CPU1_SB_CA<2>";
168"M_E_CPU1_SA_CA<2>";
169"M_E_CPU1_SB_CA<1>";
170"M_E_CPU1_SA_CA<1>";
171"M_E_CPU1_SB_CA<0>";
172"M_E_CPU1_SA_CA<0>";
173"M_E_CPU1_SB_CB<7>";
174"M_E_CPU1_SA_CB<1>";
175"M_E_CPU1_SA_CB<4>";
176"M_E_CPU1_SA_CB<7>";
177"M_E_CPU1_SA_DQ<31>";
178"PD_CHE_CPU1_DIMM_SAA";
%"VCC_CORE"
"1","(-8700,3675)","0","mstr_symbols","I1";
;
HDL_POWER"P3V3_STBY"
CDS_LIB"mstr_symbols"
VOLTAGE"3.3"
ROOM"PVCCINFAON_CPU1_CTRL";
"A"14;
%"TAP"
"1","(-6175,4450)","0","mstr_standard","I100";
;
CDS_LIB"mstr_standard"
BODY_TYPE"PLUMBING"
HDL_TAP"TRUE";
"B \NAC \NWC"5;
"S \NAC"
BN"7"117;
%"TAP"
"1","(-6175,4500)","0","mstr_standard","I101";
;
CDS_LIB"mstr_standard"
BODY_TYPE"PLUMBING"
HDL_TAP"TRUE";
"B \NAC \NWC"5;
"S \NAC"
BN"8"118;
%"TAP"
"1","(-6175,4550)","0","mstr_standard","I102";
;
CDS_LIB"mstr_standard"
BODY_TYPE"PLUMBING"
HDL_TAP"TRUE";
"B \NAC \NWC"5;
"S \NAC"
BN"9"119;
%"TAP"
"1","(-6175,4650)","0","mstr_standard","I103";
;
CDS_LIB"mstr_standard"
BODY_TYPE"PLUMBING"
HDL_TAP"TRUE";
"B \NAC \NWC"5;
"S \NAC"
BN"11"121;
%"TAP"
"1","(-6175,4600)","0","mstr_standard","I104";
;
CDS_LIB"mstr_standard"
BODY_TYPE"PLUMBING"
HDL_TAP"TRUE";
"B \NAC \NWC"5;
"S \NAC"
BN"10"120;
%"TAP"
"1","(-6175,4800)","0","mstr_standard","I105";
;
CDS_LIB"mstr_standard"
BODY_TYPE"PLUMBING"
HDL_TAP"TRUE";
"B \NAC \NWC"5;
"S \NAC"
BN"14"124;
%"TAP"
"1","(-6175,4750)","0","mstr_standard","I106";
;
CDS_LIB"mstr_standard"
BODY_TYPE"PLUMBING"
HDL_TAP"TRUE";
"B \NAC \NWC"5;
"S \NAC"
BN"13"123;
%"TAP"
"1","(-6175,4700)","0","mstr_standard","I107";
;
CDS_LIB"mstr_standard"
BODY_TYPE"PLUMBING"
HDL_TAP"TRUE";
"B \NAC \NWC"5;
"S \NAC"
BN"12"122;
%"TAP"
"1","(-6175,4850)","0","mstr_standard","I108";
;
CDS_LIB"mstr_standard"
BODY_TYPE"PLUMBING"
HDL_TAP"TRUE";
"B \NAC \NWC"5;
"S \NAC"
BN"15"125;
%"TAP"
"1","(-6175,4900)","0","mstr_standard","I109";
;
CDS_LIB"mstr_standard"
BODY_TYPE"PLUMBING"
HDL_TAP"TRUE";
"B \NAC \NWC"5;
"S \NAC"
BN"16"126;
%"TAP"
"1","(-7875,3450)","2","mstr_standard","I11";
;
CDS_LIB"mstr_standard"
BODY_TYPE"PLUMBING"
HDL_TAP"TRUE";
"B \NAC \NWC"4;
"S \NAC"
BN"0"147;
%"TAP"
"1","(-6175,4950)","0","mstr_standard","I110";
;
CDS_LIB"mstr_standard"
BODY_TYPE"PLUMBING"
HDL_TAP"TRUE";
"B \NAC \NWC"5;
"S \NAC"
BN"17"127;
%"TAP"
"1","(-6175,5000)","0","mstr_standard","I111";
;
CDS_LIB"mstr_standard"
BODY_TYPE"PLUMBING"
HDL_TAP"TRUE";
"B \NAC \NWC"5;
"S \NAC"
BN"18"128;
%"TAP"
"1","(-6175,5050)","0","mstr_standard","I112";
;
CDS_LIB"mstr_standard"
BODY_TYPE"PLUMBING"
HDL_TAP"TRUE";
"B \NAC \NWC"5;
"S \NAC"
BN"19"129;
%"TAP"
"1","(-6175,5100)","0","mstr_standard","I113";
;
CDS_LIB"mstr_standard"
BODY_TYPE"PLUMBING"
HDL_TAP"TRUE";
"B \NAC \NWC"5;
"S \NAC"
BN"20"130;
%"TAP"
"1","(-6175,5150)","0","mstr_standard","I114";
;
CDS_LIB"mstr_standard"
BODY_TYPE"PLUMBING"
HDL_TAP"TRUE";
"B \NAC \NWC"5;
"S \NAC"
BN"21"131;
%"TAP"
"1","(-6175,5250)","0","mstr_standard","I115";
;
CDS_LIB"mstr_standard"
BODY_TYPE"PLUMBING"
HDL_TAP"TRUE";
"B \NAC \NWC"5;
"S \NAC"
BN"23"133;
%"TAP"
"1","(-6175,5200)","0","mstr_standard","I116";
;
CDS_LIB"mstr_standard"
BODY_TYPE"PLUMBING"
HDL_TAP"TRUE";
"B \NAC \NWC"5;
"S \NAC"
BN"22"132;
%"TAP"
"1","(-6175,5300)","0","mstr_standard","I117";
;
CDS_LIB"mstr_standard"
BODY_TYPE"PLUMBING"
HDL_TAP"TRUE";
"B \NAC \NWC"5;
"S \NAC"
BN"24"134;
%"TAP"
"1","(-6175,5450)","0","mstr_standard","I118";
;
CDS_LIB"mstr_standard"
BODY_TYPE"PLUMBING"
HDL_TAP"TRUE";
"B \NAC \NWC"5;
"S \NAC"
BN"27"137;
%"TAP"
"1","(-6175,5400)","0","mstr_standard","I119";
;
CDS_LIB"mstr_standard"
BODY_TYPE"PLUMBING"
HDL_TAP"TRUE";
"B \NAC \NWC"5;
"S \NAC"
BN"26"136;
%"TAP"
"1","(-7875,3500)","2","mstr_standard","I12";
;
CDS_LIB"mstr_standard"
BODY_TYPE"PLUMBING"
HDL_TAP"TRUE";
"B \NAC \NWC"4;
"S \NAC"
BN"1"148;
%"TAP"
"1","(-6175,5350)","0","mstr_standard","I120";
;
CDS_LIB"mstr_standard"
BODY_TYPE"PLUMBING"
HDL_TAP"TRUE";
"B \NAC \NWC"5;
"S \NAC"
BN"25"135;
%"TAP"
"1","(-6175,5500)","0","mstr_standard","I121";
;
CDS_LIB"mstr_standard"
BODY_TYPE"PLUMBING"
HDL_TAP"TRUE";
"B \NAC \NWC"5;
"S \NAC"
BN"28"138;
%"TAP"
"1","(-6175,5550)","0","mstr_standard","I122";
;
CDS_LIB"mstr_standard"
BODY_TYPE"PLUMBING"
HDL_TAP"TRUE";
"B \NAC \NWC"5;
"S \NAC"
BN"29"139;
%"TAP"
"1","(-6175,5650)","0","mstr_standard","I123";
;
CDS_LIB"mstr_standard"
BODY_TYPE"PLUMBING"
HDL_TAP"TRUE";
"B \NAC \NWC"5;
"S \NAC"
BN"31"177;
%"TAP"
"1","(-6175,5600)","0","mstr_standard","I124";
;
CDS_LIB"mstr_standard"
BODY_TYPE"PLUMBING"
HDL_TAP"TRUE";
"B \NAC \NWC"5;
"S \NAC"
BN"30"140;
%"GND"
"1","(-6575,1250)","0","mstr_symbols","I126";
;
BOM_COST"MEM"
SIZE"1B"
CDS_LIB"mstr_symbols"
BODY_TYPE"PLUMBING"
VOLTAGE"0.0"
HDL_POWER"GND";
"A\NAC"11;
%"Q_RES"
"2","(-6575,1475)","0","pure_quanta","I127";
;
LOCATION"R6"
SEC"1"
WATTAGE"1/16W"
MATERIAL"CHIP"
TOLERANCE"1%"
VALUE"54.9K"
PART_NUMBER"TMP_QCS35492FB14"
PACK_TYPE"0402LF"
BOM_COST"MEM"
CDS_LIB"pure_quanta"
SEC_TYPE"0402LF";
"A"
$PN"1"
XNET_PINS"3"178;
"B"
$PN"2"
XNET_PINS"2"11;
%"TAP"
"1","(-7875,3550)","2","mstr_standard","I13";
;
CDS_LIB"mstr_standard"
BODY_TYPE"PLUMBING"
HDL_TAP"TRUE";
"B \NAC \NWC"4;
"S \NAC"
BN"2"149;
%"TAP"
"1","(-7875,3600)","2","mstr_standard","I14";
;
CDS_LIB"mstr_standard"
BODY_TYPE"PLUMBING"
HDL_TAP"TRUE";
"B \NAC \NWC"4;
"S \NAC"
BN"3"150;
%"GND"
"1","(-2175,2250)","0","mstr_symbols","I140";
;
CDS_LIB"mstr_symbols"
SIZE"1B"
BODY_TYPE"PLUMBING"
VOLTAGE"0.0"
HDL_POWER"GND";
"A\NAC"28;
%"GND"
"1","(-375,2075)","0","mstr_symbols","I141";
;
CDS_LIB"mstr_symbols"
SIZE"1B"
BODY_TYPE"PLUMBING"
VOLTAGE"0.0"
HDL_POWER"GND";
"A\NAC"27;
%"TAP"
"1","(-7875,3650)","2","mstr_standard","I15";
;
CDS_LIB"mstr_standard"
BODY_TYPE"PLUMBING"
HDL_TAP"TRUE";
"B \NAC \NWC"4;
"S \NAC"
BN"4"151;
%"TAP"
"1","(-7875,3700)","2","mstr_standard","I16";
;
CDS_LIB"mstr_standard"
BODY_TYPE"PLUMBING"
HDL_TAP"TRUE";
"B \NAC \NWC"4;
"S \NAC"
BN"5"152;
%"TAP"
"1","(-7875,3750)","2","mstr_standard","I17";
;
CDS_LIB"mstr_standard"
BODY_TYPE"PLUMBING"
HDL_TAP"TRUE";
"B \NAC \NWC"4;
"S \NAC"
BN"6"153;
%"SCONN288_DDR506112002KQ"
"3","(-1275,4000)","0","pure_quanta","I175";
;
LOCATION"J32"
$SEC"3"
CDS_SEC"3"
PART_TYPE"SMLF"
MATERIAL"IO"
VALUE"SCONN288_DDR506112002KQ"
PART_NUMBER"DFHST8FS479"
CDS_LMAN_SYM_OUTLINE"-450,1800,450,-1750"
NEEDS_NO_SIZE"TRUE"
CDS_LIB"pure_quanta";
"G3"
$PN"G3"27;
"G2"
$PN"G2"27;
"G1"
$PN"G1"27;
"VSS62"
$PN"141"27;
"VSS61"
$PN"139"27;
"VSS60"
$PN"136"27;
"VSS58"
$PN"132"27;
"VSS104"
$PN"240"28;
"VSS102"
$PN"235"28;
"VSS100"
$PN"230"28;
"VIN_BULK2"
$PN"146"25;
"VIN_BULK1"
$PN"145"25;
"VIN_BULK0"
$PN"1"25;
"VSS126"
$PN"288"28;
"VSS125"
$PN"286"28;
"VSS124"
$PN"284"28;
"VSS123"
$PN"281"28;
"VSS122"
$PN"279"28;
"VSS121"
$PN"277"28;
"VSS120"
$PN"275"28;
"VSS119"
$PN"273"28;
"VSS118"
$PN"270"28;
"VSS117"
$PN"268"28;
"VSS116"
$PN"266"28;
"VSS115"
$PN"264"28;
"VSS114"
$PN"262"28;
"VSS113"
$PN"259"28;
"VSS112"
$PN"257"28;
"VSS111"
$PN"255"28;
"VSS110"
$PN"253"28;
"VSS109"
$PN"251"28;
"VSS108"
$PN"248"28;
"VSS107"
$PN"246"28;
"VSS106"
$PN"244"28;
"VSS105"
$PN"242"28;
"VSS103"
$PN"237"28;
"VSS101"
$PN"233"28;
"VSS99"
$PN"228"28;
"VSS98"
$PN"226"28;
"VSS97"
$PN"224"28;
"VSS96"
$PN"222"28;
"VSS95"
$PN"219"28;
"VSS94"
$PN"216"28;
"VSS93"
$PN"214"28;
"VSS92"
$PN"212"28;
"VSS91"
$PN"210"28;
"VSS90"
$PN"208"28;
"VSS89"
$PN"206"28;
"VSS88"
$PN"204"28;
"VSS87"
$PN"202"28;
"VSS86"
$PN"199"28;
"VSS85"
$PN"197"28;
"VSS84"
$PN"195"28;
"VSS83"
$PN"193"28;
"VSS82"
$PN"191"28;
"VSS81"
$PN"188"28;
"VSS80"
$PN"186"28;
"VSS79"
$PN"184"28;
"VSS78"
$PN"182"28;
"VSS77"
$PN"180"28;
"VSS76"
$PN"177"28;
"VSS75"
$PN"175"28;
"VSS74"
$PN"173"28;
"VSS73"
$PN"171"28;
"VSS72"
$PN"169"28;
"VSS71"
$PN"166"28;
"VSS70"
$PN"164"28;
"VSS69"
$PN"162"28;
"VSS68"
$PN"160"28;
"VSS67"
$PN"158"28;
"VSS66"
$PN"155"28;
"VSS65"
$PN"153"28;
"VSS64"
$PN"151"28;
"VSS63"
$PN"143"27;
"VSS59"
$PN"134"27;
"VSS57"
$PN"130"27;
"VSS56"
$PN"128"27;
"VSS55"
$PN"125"27;
"VSS54"
$PN"123"27;
"VSS53"
$PN"121"27;
"VSS52"
$PN"119"27;
"VSS51"
$PN"117"27;
"VSS50"
$PN"114"27;
"VSS49"
$PN"112"27;
"VSS48"
$PN"110"27;
"VSS47"
$PN"108"27;
"VSS46"
$PN"106"27;
"VSS45"
$PN"103"27;
"VSS44"
$PN"101"27;
"VSS43"
$PN"99"27;
"VSS42"
$PN"97"27;
"VSS41"
$PN"95"27;
"VSS40"
$PN"92"27;
"VSS39"
$PN"90"27;
"VSS38"
$PN"88"27;
"VSS37"
$PN"85"27;
"VSS36"
$PN"83"27;
"VSS35"
$PN"81"27;
"VSS34"
$PN"79"27;
"VSS33"
$PN"77"27;
"VSS32"
$PN"75"27;
"VSS31"
$PN"73"27;
"VSS30"
$PN"71"27;
"VSS29"
$PN"69"27;
"VSS28"
$PN"67"27;
"VSS27"
$PN"65"27;
"VSS26"
$PN"63"27;
"VSS25"
$PN"61"27;
"VSS24"
$PN"59"27;
"VSS23"
$PN"57"27;
"VSS22"
$PN"54"27;
"VSS21"
$PN"52"27;
"VSS20"
$PN"50"27;
"VSS19"
$PN"48"27;
"VSS18"
$PN"46"27;
"VSS17"
$PN"43"27;
"VSS16"
$PN"41"27;
"VSS15"
$PN"39"27;
"VSS14"
$PN"37"27;
"VSS13"
$PN"35"27;
"VSS12"
$PN"32"27;
"VSS11"
$PN"30"27;
"VSS10"
$PN"28"27;
"VSS9"
$PN"26"27;
"VSS8"
$PN"24"27;
"VSS7"
$PN"21"27;
"VSS6"
$PN"19"27;
"VSS5"
$PN"17"27;
"VSS4"
$PN"15"27;
"VSS3"
$PN"13"27;
"VSS2"
$PN"10"27;
"VSS1"
$PN"8"27;
"VSS0"
$PN"6"27;
%"TAP"
"1","(-7875,3900)","2","mstr_standard","I18";
;
CDS_LIB"mstr_standard"
BODY_TYPE"PLUMBING"
HDL_TAP"TRUE";
"B \NAC \NWC"1;
"S \NAC"
BN"0"154;
%"Q_CAP"
"1","(-8800,3475)","2","pure_quanta","I185";
;
LOCATION"C152"
$SEC"1"
CDS_SEC"1"
MATERIAL"X7R"
TOLERANCE"10%"
VOLTAGE"25V"
VALUE"0.1UF"
PACK_TYPE"0402"
PART_NUMBER"CH4104K1B00"
CDS_LIB"pure_quanta"
BOM_COST"MEM"
ROOM"MEM_CH_A_CPU0_DIMM1";
"B"
$PN"2"12;
"A"
$PN"1"14;
%"GND"
"1","(-8800,3250)","0","mstr_symbols","I186";
;
CDS_LIB"mstr_symbols"
SIZE"1B"
BOM_COST"MEM"
BODY_TYPE"PLUMBING"
VOLTAGE"0"
ROOM"MEM_EFGH_DECOUPLING_CAPS"
HDL_POWER"GND";
"A\NAC"12;
%"Q_RES"
"1","(-8625,2400)","2","pure_quanta","I188";
;
LOCATION"R307"
$SEC"1"
CDS_SEC"1"
VALUE"0"
CDS_LIB"pure_quanta"
BOM_COST"MEM"
WATTAGE"1/16W"
MATERIAL"CHIP"
TOLERANCE"5%"
PART_NUMBER"CS00002JB38"
PACK_TYPE"0402LF"
ROOM"RST_CPU0_PLD_TO_DIMM";
"B"
$PN"2"24;
"A"
$PN"1"18;
%"VCC_CORE"
"1","(-8500,2725)","0","mstr_symbols","I189";
;
HDL_POWER"P3V3_STBY"
CDS_LIB"mstr_symbols"
VOLTAGE"3.3"
ROOM"PVCCINFAON_CPU0_CTRL";
"A"13;
%"TAP"
"1","(-7875,3800)","2","mstr_standard","I19";
;
CDS_LIB"mstr_standard"
BODY_TYPE"PLUMBING"
HDL_TAP"TRUE";
"B \NAC \NWC"4;
"S \NAC"
BN"7"173;
%"Q_RES"
"2","(-8500,2550)","0","pure_quanta","I190";
;
LOCATION"R107"
$SEC"1"
CDS_SEC"1"
WATTAGE"1/16W"
MATERIAL"EMPTY"
TOLERANCE"5%"
VALUE"1K"
PACK_TYPE"0402LF"
BOM_COST"MEM"
CDS_LIB"pure_quanta"
PART_NUMBER"TMP_QCS21002JB34"
ROOM"MEM_CH_A_CPU0_DIMM1";
"A"
$PN"1"13;
"B"
$PN"2"18;
%"TAP"
"1","(-3475,3875)","0","mstr_standard","I192";
;
CDS_LIB"mstr_standard"
BODY_TYPE"PLUMBING"
HDL_TAP"TRUE";
"B \NAC \NWC"8;
"S \NAC"
BN"0"62;
%"TAP"
"1","(-3275,4025)","0","mstr_standard","I193";
;
CDS_LIB"mstr_standard"
BODY_TYPE"PLUMBING"
HDL_TAP"TRUE";
"B \NAC \NWC"7;
"S \NAC"
BN"2"55;
%"TAP"
"1","(-3275,4625)","0","mstr_standard","I198";
;
CDS_LIB"mstr_standard"
BODY_TYPE"PLUMBING"
HDL_TAP"TRUE";
"B \NAC \NWC"7;
"S \NAC"
BN"8"34;
%"TAP"
"1","(-3275,4725)","0","mstr_standard","I199";
;
CDS_LIB"mstr_standard"
BODY_TYPE"PLUMBING"
HDL_TAP"TRUE";
"B \NAC \NWC"7;
"S \NAC"
BN"9"32;
%"TAP"
"1","(-7875,4000)","2","mstr_standard","I20";
;
CDS_LIB"mstr_standard"
BODY_TYPE"PLUMBING"
HDL_TAP"TRUE";
"B \NAC \NWC"1;
"S \NAC"
BN"2"155;
%"TAP"
"1","(-3275,4425)","0","mstr_standard","I200";
;
CDS_LIB"mstr_standard"
BODY_TYPE"PLUMBING"
HDL_TAP"TRUE";
"B \NAC \NWC"7;
"S \NAC"
BN"6"39;
%"TAP"
"1","(-3275,4525)","0","mstr_standard","I201";
;
CDS_LIB"mstr_standard"
BODY_TYPE"PLUMBING"
HDL_TAP"TRUE";
"B \NAC \NWC"7;
"S \NAC"
BN"7"68;
%"TAP"
"1","(-3275,4325)","0","mstr_standard","I202";
;
CDS_LIB"mstr_standard"
BODY_TYPE"PLUMBING"
HDL_TAP"TRUE";
"B \NAC \NWC"7;
"S \NAC"
BN"5"43;
%"TAP"
"1","(-3475,4775)","0","mstr_standard","I203";
;
CDS_LIB"mstr_standard"
BODY_TYPE"PLUMBING"
HDL_TAP"TRUE";
"B \NAC \NWC"8;
"S \NAC"
BN"9"31;
%"TAP"
"1","(-3475,4675)","0","mstr_standard","I204";
;
CDS_LIB"mstr_standard"
BODY_TYPE"PLUMBING"
HDL_TAP"TRUE";
"B \NAC \NWC"8;
"S \NAC"
BN"8"33;
%"TAP"
"1","(-3475,4575)","0","mstr_standard","I205";
;
CDS_LIB"mstr_standard"
BODY_TYPE"PLUMBING"
HDL_TAP"TRUE";
"B \NAC \NWC"8;
"S \NAC"
BN"7"36;
%"TAP"
"1","(-3475,4475)","0","mstr_standard","I206";
;
CDS_LIB"mstr_standard"
BODY_TYPE"PLUMBING"
HDL_TAP"TRUE";
"B \NAC \NWC"8;
"S \NAC"
BN"6"67;
%"TAP"
"1","(-3475,4375)","0","mstr_standard","I207";
;
CDS_LIB"mstr_standard"
BODY_TYPE"PLUMBING"
HDL_TAP"TRUE";
"B \NAC \NWC"8;
"S \NAC"
BN"5"42;
%"TAP"
"1","(-3275,4225)","0","mstr_standard","I208";
;
CDS_LIB"mstr_standard"
BODY_TYPE"PLUMBING"
HDL_TAP"TRUE";
"B \NAC \NWC"7;
"S \NAC"
BN"4"47;
%"TAP"
"1","(-3275,4125)","0","mstr_standard","I209";
;
CDS_LIB"mstr_standard"
BODY_TYPE"PLUMBING"
HDL_TAP"TRUE";
"B \NAC \NWC"7;
"S \NAC"
BN"3"51;
%"TAP"
"1","(-7875,3950)","2","mstr_standard","I21";
;
CDS_LIB"mstr_standard"
BODY_TYPE"PLUMBING"
HDL_TAP"TRUE";
"B \NAC \NWC"1;
"S \NAC"
BN"1"174;
%"TAP"
"1","(-3275,3925)","0","mstr_standard","I210";
;
CDS_LIB"mstr_standard"
BODY_TYPE"PLUMBING"
HDL_TAP"TRUE";
"B \NAC \NWC"7;
"S \NAC"
BN"1"59;
%"TAP"
"1","(-3275,3825)","0","mstr_standard","I211";
;
CDS_LIB"mstr_standard"
BODY_TYPE"PLUMBING"
HDL_TAP"TRUE";
"B \NAC \NWC"7;
"S \NAC"
BN"0"63;
%"TAP"
"1","(-3475,4275)","0","mstr_standard","I212";
;
CDS_LIB"mstr_standard"
BODY_TYPE"PLUMBING"
HDL_TAP"TRUE";
"B \NAC \NWC"8;
"S \NAC"
BN"4"46;
%"TAP"
"1","(-3475,4175)","0","mstr_standard","I213";
;
CDS_LIB"mstr_standard"
BODY_TYPE"PLUMBING"
HDL_TAP"TRUE";
"B \NAC \NWC"8;
"S \NAC"
BN"3"50;
%"TAP"
"1","(-3475,4075)","0","mstr_standard","I214";
;
CDS_LIB"mstr_standard"
BODY_TYPE"PLUMBING"
HDL_TAP"TRUE";
"B \NAC \NWC"8;
"S \NAC"
BN"2"54;
%"TAP"
"1","(-3475,3975)","0","mstr_standard","I215";
;
CDS_LIB"mstr_standard"
BODY_TYPE"PLUMBING"
HDL_TAP"TRUE";
"B \NAC \NWC"8;
"S \NAC"
BN"1"58;
%"TAP"
"1","(-3275,3575)","0","mstr_standard","I216";
;
CDS_LIB"mstr_standard"
BODY_TYPE"PLUMBING"
HDL_TAP"TRUE";
"B \NAC \NWC"9;
"S \NAC"
BN"8"65;
%"TAP"
"1","(-3275,3675)","0","mstr_standard","I217";
;
CDS_LIB"mstr_standard"
BODY_TYPE"PLUMBING"
HDL_TAP"TRUE";
"B \NAC \NWC"9;
"S \NAC"
BN"9"30;
%"TAP"
"1","(-3275,3375)","0","mstr_standard","I218";
;
CDS_LIB"mstr_standard"
BODY_TYPE"PLUMBING"
HDL_TAP"TRUE";
"B \NAC \NWC"9;
"S \NAC"
BN"6"38;
%"TAP"
"1","(-3275,3475)","0","mstr_standard","I219";
;
CDS_LIB"mstr_standard"
BODY_TYPE"PLUMBING"
HDL_TAP"TRUE";
"B \NAC \NWC"9;
"S \NAC"
BN"7"35;
%"TAP"
"1","(-7875,4050)","2","mstr_standard","I22";
;
CDS_LIB"mstr_standard"
BODY_TYPE"PLUMBING"
HDL_TAP"TRUE";
"B \NAC \NWC"1;
"S \NAC"
BN"3"156;
%"TAP"
"1","(-3475,3725)","0","mstr_standard","I220";
;
CDS_LIB"mstr_standard"
BODY_TYPE"PLUMBING"
HDL_TAP"TRUE";
"B \NAC \NWC"10;
"S \NAC"
BN"9"29;
%"TAP"
"1","(-3475,3625)","0","mstr_standard","I221";
;
CDS_LIB"mstr_standard"
BODY_TYPE"PLUMBING"
HDL_TAP"TRUE";
"B \NAC \NWC"10;
"S \NAC"
BN"8"66;
%"TAP"
"1","(-3475,3525)","0","mstr_standard","I222";
;
CDS_LIB"mstr_standard"
BODY_TYPE"PLUMBING"
HDL_TAP"TRUE";
"B \NAC \NWC"10;
"S \NAC"
BN"7"64;
%"TAP"
"1","(-3475,3425)","0","mstr_standard","I223";
;
CDS_LIB"mstr_standard"
BODY_TYPE"PLUMBING"
HDL_TAP"TRUE";
"B \NAC \NWC"10;
"S \NAC"
BN"6"37;
%"TAP"
"1","(-3475,3325)","0","mstr_standard","I224";
;
CDS_LIB"mstr_standard"
BODY_TYPE"PLUMBING"
HDL_TAP"TRUE";
"B \NAC \NWC"10;
"S \NAC"
BN"5"40;
%"TAP"
"1","(-3275,3075)","0","mstr_standard","I225";
;
CDS_LIB"mstr_standard"
BODY_TYPE"PLUMBING"
HDL_TAP"TRUE";
"B \NAC \NWC"9;
"S \NAC"
BN"3"49;
%"TAP"
"1","(-3275,3275)","0","mstr_standard","I226";
;
CDS_LIB"mstr_standard"
BODY_TYPE"PLUMBING"
HDL_TAP"TRUE";
"B \NAC \NWC"9;
"S \NAC"
BN"5"41;
%"TAP"
"1","(-3275,3175)","0","mstr_standard","I227";
;
CDS_LIB"mstr_standard"
BODY_TYPE"PLUMBING"
HDL_TAP"TRUE";
"B \NAC \NWC"9;
"S \NAC"
BN"4"45;
%"TAP"
"1","(-3275,2875)","0","mstr_standard","I228";
;
CDS_LIB"mstr_standard"
BODY_TYPE"PLUMBING"
HDL_TAP"TRUE";
"B \NAC \NWC"9;
"S \NAC"
BN"1"57;
%"TAP"
"1","(-3275,2975)","0","mstr_standard","I229";
;
CDS_LIB"mstr_standard"
BODY_TYPE"PLUMBING"
HDL_TAP"TRUE";
"B \NAC \NWC"9;
"S \NAC"
BN"2"53;
%"TAP"
"1","(-7875,4100)","2","mstr_standard","I23";
;
CDS_LIB"mstr_standard"
BODY_TYPE"PLUMBING"
HDL_TAP"TRUE";
"B \NAC \NWC"1;
"S \NAC"
BN"4"175;
%"TAP"
"1","(-3475,3225)","0","mstr_standard","I230";
;
CDS_LIB"mstr_standard"
BODY_TYPE"PLUMBING"
HDL_TAP"TRUE";
"B \NAC \NWC"10;
"S \NAC"
BN"4"44;
%"TAP"
"1","(-3475,3125)","0","mstr_standard","I231";
;
CDS_LIB"mstr_standard"
BODY_TYPE"PLUMBING"
HDL_TAP"TRUE";
"B \NAC \NWC"10;
"S \NAC"
BN"3"48;
%"TAP"
"1","(-3475,3025)","0","mstr_standard","I232";
;
CDS_LIB"mstr_standard"
BODY_TYPE"PLUMBING"
HDL_TAP"TRUE";
"B \NAC \NWC"10;
"S \NAC"
BN"2"52;
%"TAP"
"1","(-3475,2925)","0","mstr_standard","I233";
;
CDS_LIB"mstr_standard"
BODY_TYPE"PLUMBING"
HDL_TAP"TRUE";
"B \NAC \NWC"10;
"S \NAC"
BN"1"56;
%"TAP"
"1","(-3475,2825)","0","mstr_standard","I234";
;
CDS_LIB"mstr_standard"
BODY_TYPE"PLUMBING"
HDL_TAP"TRUE";
"B \NAC \NWC"10;
"S \NAC"
BN"0"60;
%"TAP"
"1","(-3275,2775)","0","mstr_standard","I235";
;
CDS_LIB"mstr_standard"
BODY_TYPE"PLUMBING"
HDL_TAP"TRUE";
"B \NAC \NWC"9;
"S \NAC"
BN"0"61;
%"SCONN288_DDR506112002KQ"
"2","(-4425,3775)","0","pure_quanta","I236";
;
LOCATION"J32"
$SEC"2"
CDS_SEC"2"
MATERIAL"IO"
PART_TYPE"SMLF"
VALUE"SCONN288_DDR506112002KQ"
PART_NUMBER"DFHST8FS479"
CDS_LMAN_SYM_OUTLINE"-600,1150,600,-1150"
NEEDS_NO_SIZE"TRUE"
CDS_LIB"pure_quanta";
"DQS7_A_C||TDQS7_A_C \B"
$PN"178"68;
"DQS6_A_T||TDQS6_A_T"
$PN"168"67;
"DQS8_B_T||TDQS8_B_T"
$PN"283"66;
"DQS8_B_C||TDQS8_B_C \B"
$PN"282"65;
"DQS7_B_T||TDQS7_B_T"
$PN"272"64;
"DQS0_A_C \B"
$PN"12"63;
"DQS0_A_T"
$PN"11"62;
"DQS0_B_C \B"
$PN"105"61;
"DQS0_B_T"
$PN"104"60;
"DQS1_A_C \B"
$PN"23"59;
"DQS1_A_T"
$PN"22"58;
"DQS1_B_C \B"
$PN"116"57;
"DQS1_B_T"
$PN"115"56;
"DQS2_A_C \B"
$PN"34"55;
"DQS2_A_T"
$PN"33"54;
"DQS2_B_C \B"
$PN"127"53;
"DQS2_B_T"
$PN"126"52;
"DQS3_A_C \B"
$PN"45"51;
"DQS3_A_T"
$PN"44"50;
"DQS3_B_C \B"
$PN"138"49;
"DQS3_B_T"
$PN"137"48;
"DQS4_A_C \B"
$PN"56"47;
"DQS4_A_T"
$PN"55"46;
"DQS4_B_C \B"
$PN"238"45;
"DQS4_B_T"
$PN"239"44;
"DQS5_A_C||TDQS5_A_C||DQS5_A_T||TDQS5_A_T \B"
$PN"156"43;
"DQS5_A_T||TDQS5_A_T"
$PN"157"42;
"DQS5_B_C||TDQS5_B_C \B"
$PN"249"41;
"DQS5_B_T||TDQS5_B_T"
$PN"250"40;
"DQS6_A_C||TDQS6_A_C||DQS6_A_T||TDQS6_A_T \B"
$PN"167"39;
"DQS6_B_C||TDQS6_B_C \B"
$PN"260"38;
"DQS6_B_T||TDQS6_B_T"
$PN"261"37;
"DQS7_A_T||TDQS7_A_T"
$PN"179"36;
"DQS7_B_C||TDQS7_B_C \B"
$PN"271"35;
"DQS8_A_C||TDQS8_A_C \B"
$PN"189"34;
"DQS8_A_T||TDQS8_A_T"
$PN"190"33;
"DQS9_A_C||TDQS9_A_C \B"
$PN"200"32;
"DQS9_A_T||TDQS9_A_T"
$PN"201"31;
"DQS9_B_C||TDQS9_B_C \B"
$PN"94"30;
"DQS9_B_T||TDQS9_B_T||DBI4_B_N"
$PN"93"29;
%"GND"
"1","(-2875,5825)","0","pure_quanta_power","I237";
;
CDS_LIB"pure_quanta_power"
BOM_COST"MEM"
SIZE"1B"
ROOM"MEM_EFGH_DECOUPLING_CAPS"
HDL_POWER"GND";
"A<SIZE-1..0>\NAC"26;
%"Q_CAP"
"1","(-2875,6175)","2","pure_quanta","I238";
;
LOCATION"C183"
$SEC"1"
CDS_SEC"1"
MATERIAL"X6S"
TOLERANCE"10%"
VALUE"10UF"
VOLTAGE"25V"
PACK_TYPE"C0805"
PART_NUMBER"CH6104KEA00"
BOM_COST"MEM"
CDS_LIB"pure_quanta"
ROOM"MEM_CH_A_CPU0_DIMM1";
"B"
$PN"2"26;
"A"
$PN"1"25;
%"Q_CAP"
"1","(-2300,6175)","2","pure_quanta","I239";
;
LOCATION"C509"
$SEC"1"
CDS_SEC"1"
MATERIAL"X6S"
TOLERANCE"10%"
VALUE"10UF"
PART_NUMBER"CH6104KEA00"
VOLTAGE"25V"
PACK_TYPE"C0805"
BOM_COST"MEM"
CDS_LIB"pure_quanta"
ROOM"MEM_CH_A_CPU0_DIMM1";
"B"
$PN"2"26;
"A"
$PN"1"25;
%"TAP"
"1","(-7875,4150)","2","mstr_standard","I24";
;
CDS_LIB"mstr_standard"
BODY_TYPE"PLUMBING"
HDL_TAP"TRUE";
"B \NAC \NWC"1;
"S \NAC"
BN"5"157;
%"UNIVERSAL_POWER"
"1","(-2875,6500)","0","pure_quanta_power","I240";
;
HDL_POWER"P12V_MEM_2"
CDS_LIB"pure_quanta_power";
"A"25;
%"Q_RES"
"1","(-7925,2925)","0","pure_quanta","I242";
;
$LOCATION"R1584"
CDS_LOCATION"R1584"
$SEC"1"
CDS_SEC"1"
VALUE"49.9"
CDS_LIB"pure_quanta"
PART_NUMBER"CS04992FB07"
TOLERANCE"1%"
WATTAGE"1/16W"
PACK_TYPE"0402LF"
MATERIAL"CHIP";
"B"
$PN"2"16;
"A"
$PN"1"17;
%"TAP"
"1","(-7875,4200)","2","mstr_standard","I34";
;
CDS_LIB"mstr_standard"
BODY_TYPE"PLUMBING"
HDL_TAP"TRUE";
"B \NAC \NWC"1;
"S \NAC"
BN"6"158;
%"TAP"
"1","(-7875,4250)","2","mstr_standard","I35";
;
CDS_LIB"mstr_standard"
BODY_TYPE"PLUMBING"
HDL_TAP"TRUE";
"B \NAC \NWC"1;
"S \NAC"
BN"7"176;
%"TAP"
"1","(-7875,5000)","2","mstr_standard","I36";
;
CDS_LIB"mstr_standard"
BODY_TYPE"PLUMBING"
HDL_TAP"TRUE";
"B \NAC \NWC"3;
"S \NAC"
BN"1"169;
%"TAP"
"1","(-7875,4950)","2","mstr_standard","I37";
;
CDS_LIB"mstr_standard"
BODY_TYPE"PLUMBING"
HDL_TAP"TRUE";
"B \NAC \NWC"3;
"S \NAC"
BN"0"171;
%"TAP"
"1","(-7875,5050)","2","mstr_standard","I38";
;
CDS_LIB"mstr_standard"
BODY_TYPE"PLUMBING"
HDL_TAP"TRUE";
"B \NAC \NWC"3;
"S \NAC"
BN"2"167;
%"TAP"
"1","(-7875,5100)","2","mstr_standard","I39";
;
CDS_LIB"mstr_standard"
BODY_TYPE"PLUMBING"
HDL_TAP"TRUE";
"B \NAC \NWC"3;
"S \NAC"
BN"3"165;
%"TAP"
"1","(-7875,5150)","2","mstr_standard","I40";
;
CDS_LIB"mstr_standard"
BODY_TYPE"PLUMBING"
HDL_TAP"TRUE";
"B \NAC \NWC"3;
"S \NAC"
BN"4"163;
%"TAP"
"1","(-7875,5250)","2","mstr_standard","I43";
;
CDS_LIB"mstr_standard"
BODY_TYPE"PLUMBING"
HDL_TAP"TRUE";
"B \NAC \NWC"3;
"S \NAC"
BN"6"159;
%"TAP"
"1","(-7875,5200)","2","mstr_standard","I44";
;
CDS_LIB"mstr_standard"
BODY_TYPE"PLUMBING"
HDL_TAP"TRUE";
"B \NAC \NWC"3;
"S \NAC"
BN"5"161;
%"TAP"
"1","(-7875,5350)","2","mstr_standard","I45";
;
CDS_LIB"mstr_standard"
BODY_TYPE"PLUMBING"
HDL_TAP"TRUE";
"B \NAC \NWC"2;
"S \NAC"
BN"0"172;
%"TAP"
"1","(-7875,5400)","2","mstr_standard","I46";
;
CDS_LIB"mstr_standard"
BODY_TYPE"PLUMBING"
HDL_TAP"TRUE";
"B \NAC \NWC"2;
"S \NAC"
BN"1"170;
%"TAP"
"1","(-7875,5450)","2","mstr_standard","I47";
;
CDS_LIB"mstr_standard"
BODY_TYPE"PLUMBING"
HDL_TAP"TRUE";
"B \NAC \NWC"2;
"S \NAC"
BN"2"168;
%"TAP"
"1","(-7875,5500)","2","mstr_standard","I48";
;
CDS_LIB"mstr_standard"
BODY_TYPE"PLUMBING"
HDL_TAP"TRUE";
"B \NAC \NWC"2;
"S \NAC"
BN"3"166;
%"TAP"
"1","(-7875,5550)","2","mstr_standard","I49";
;
CDS_LIB"mstr_standard"
BODY_TYPE"PLUMBING"
HDL_TAP"TRUE";
"B \NAC \NWC"2;
"S \NAC"
BN"4"164;
%"TAP"
"1","(-7875,5600)","2","mstr_standard","I50";
;
CDS_LIB"mstr_standard"
BODY_TYPE"PLUMBING"
HDL_TAP"TRUE";
"B \NAC \NWC"2;
"S \NAC"
BN"5"162;
%"TAP"
"1","(-7875,5650)","2","mstr_standard","I51";
;
CDS_LIB"mstr_standard"
BODY_TYPE"PLUMBING"
HDL_TAP"TRUE";
"B \NAC \NWC"2;
"S \NAC"
BN"6"160;
%"SCONN288_DDR506112002KQ"
"1","(-7025,3900)","0","pure_quanta","I52";
;
LOCATION"J32"
$SEC"1"
CDS_SEC"1"
PART_TYPE"SMLF"
VALUE"SCONN288_DDR506112002KQ"
PART_NUMBER"DFHST8FS479"
MATERIAL"IO"
CDS_LMAN_SYM_OUTLINE"-450,1900,450,-1850"
NEEDS_NO_SIZE"TRUE"
CDS_LIB"pure_quanta";
"PWR_GOOD||FAIL_N"
$PN"147"18;
"DQ31_A"
$PN"194"177;
"CB7_A"
$PN"205"176;
"CB4_A"
$PN"58"175;
"CB1_A"
$PN"53"174;
"CB7_B"
$PN"236"173;
"ALERT_N \B"
$PN"62"21;
"CA0_A"
$PN"66"172;
"CA0_B"
$PN"76"171;
"CA1_A"
$PN"211"170;
"CA1_B"
$PN"221"169;
"CA2_A"
$PN"68"168;
"CA2_B"
$PN"78"167;
"CA3_A"
$PN"213"166;
"CA3_B"
$PN"223"165;
"CA4_A"
$PN"70"164;
"CA4_B"
$PN"80"163;
"CA5_A"
$PN"215"162;
"CA5_B"
$PN"225"161;
"CA6_A"
$PN"72"160;
"CA6_B"
$PN"82"159;
"CB6_A"
$PN"203"158;
"CB5_A"
$PN"60"157;
"CB3_A"
$PN"198"156;
"CB2_A"
$PN"196"155;
"CB0_A"
$PN"51"154;
"CB6_B"
$PN"234"153;
"CB5_B"
$PN"91"152;
"CB4_B"
$PN"89"151;
"CB3_B"
$PN"243"150;
"CB2_B"
$PN"241"149;
"CB1_B"
$PN"98"148;
"CB0_B"
$PN"96"147;
"CK_C \B"
$PN"218"146;
"CK_T"
$PN"217"145;
"CS0_A_N"
$PN"64"144;
"CS0_B_N"
$PN"84"143;
"CS1_A_N"
$PN"209"142;
"CS1_B_N"
$PN"229"141;
"DQ30_A"
$PN"192"140;
"DQ29_A"
$PN"49"139;
"DQ28_A"
$PN"47"138;
"DQ27_A"
$PN"187"137;
"DQ26_A"
$PN"185"136;
"DQ25_A"
$PN"42"135;
"DQ24_A"
$PN"40"134;
"DQ23_A"
$PN"183"133;
"DQ22_A"
$PN"181"132;
"DQ21_A"
$PN"38"131;
"DQ20_A"
$PN"36"130;
"DQ19_A"
$PN"176"129;
"DQ18_A"
$PN"174"128;
"DQ17_A"
$PN"31"127;
"DQ16_A"
$PN"29"126;
"DQ15_A"
$PN"172"125;
"DQ14_A"
$PN"170"124;
"DQ13_A"
$PN"27"123;
"DQ12_A"
$PN"25"122;
"DQ11_A"
$PN"165"121;
"DQ10_A"
$PN"163"120;
"DQ9_A"
$PN"20"119;
"DQ8_A"
$PN"18"118;
"DQ7_A"
$PN"161"117;
"DQ6_A"
$PN"159"116;
"DQ5_A"
$PN"16"115;
"DQ4_A"
$PN"14"114;
"DQ3_A"
$PN"154"113;
"DQ2_A"
$PN"152"112;
"DQ1_A"
$PN"9"111;
"DQ0_A"
$PN"7"110;
"DQ31_B"
$PN"287"109;
"DQ30_B"
$PN"285"108;
"DQ29_B"
$PN"142"107;
"DQ28_B"
$PN"140"106;
"DQ27_B"
$PN"280"105;
"DQ26_B"
$PN"278"104;
"DQ25_B"
$PN"135"103;
"DQ24_B"
$PN"133"102;
"DQ23_B"
$PN"276"101;
"DQ22_B"
$PN"274"100;
"DQ21_B"
$PN"131"99;
"DQ20_B"
$PN"129"98;
"DQ19_B"
$PN"269"97;
"DQ18_B"
$PN"267"96;
"DQ17_B"
$PN"124"95;
"DQ16_B"
$PN"122"94;
"DQ15_B"
$PN"265"93;
"DQ14_B"
$PN"263"92;
"DQ13_B"
$PN"120"91;
"DQ12_B"
$PN"118"90;
"DQ11_B"
$PN"258"89;
"DQ10_B"
$PN"256"88;
"DQ9_B"
$PN"113"87;
"DQ8_B"
$PN"111"86;
"DQ7_B"
$PN"254"85;
"DQ6_B"
$PN"252"84;
"DQ5_B"
$PN"109"83;
"DQ4_B"
$PN"107"82;
"DQ3_B"
$PN"247"81;
"DQ2_B"
$PN"245"80;
"DQ1_B"
$PN"102"79;
"DQ0_B"
$PN"100"78;
"HAS"
$PN"148"20;
"HSCL"
$PN"4"16;
"HSDA"
$PN"5"15;
"LBD||RSP_A_N"
$PN"86"23;
"LBS||RSP_B_N"
$PN"87"77;
"PAR_A"
$PN"74"76;
"PAR_B"
$PN"227"75;
"RESET_N \B"
$PN"207"22;
"RFU6"
$PN"232"19;
"RFU5"
$PN"231"74;
"RFU4"
$PN"220"73;
"RFU3"
$PN"150"72;
"RFU2"
$PN"149"71;
"RFU1"
$PN"144"70;
"RFU0"
$PN"2"69;
"VIN_MGMT"
$PN"3"14;
%"TAP"
"1","(-6175,2550)","0","mstr_standard","I53";
;
CDS_LIB"mstr_standard"
BODY_TYPE"PLUMBING"
HDL_TAP"TRUE";
"B \NAC \NWC"6;
"S \NAC"
BN"2"80;
%"TAP"
"1","(-6175,2600)","0","mstr_standard","I54";
;
CDS_LIB"mstr_standard"
BODY_TYPE"PLUMBING"
HDL_TAP"TRUE";
"B \NAC \NWC"6;
"S \NAC"
BN"3"81;
%"TAP"
"1","(-6175,2450)","0","mstr_standard","I55";
;
CDS_LIB"mstr_standard"
BODY_TYPE"PLUMBING"
HDL_TAP"TRUE";
"B \NAC \NWC"6;
"S \NAC"
BN"0"78;
%"TAP"
"1","(-6175,2500)","0","mstr_standard","I56";
;
CDS_LIB"mstr_standard"
BODY_TYPE"PLUMBING"
HDL_TAP"TRUE";
"B \NAC \NWC"6;
"S \NAC"
BN"1"79;
%"TAP"
"1","(-6175,2650)","0","mstr_standard","I57";
;
CDS_LIB"mstr_standard"
BODY_TYPE"PLUMBING"
HDL_TAP"TRUE";
"B \NAC \NWC"6;
"S \NAC"
BN"4"82;
%"TAP"
"1","(-6175,2700)","0","mstr_standard","I58";
;
CDS_LIB"mstr_standard"
BODY_TYPE"PLUMBING"
HDL_TAP"TRUE";
"B \NAC \NWC"6;
"S \NAC"
BN"5"83;
%"TAP"
"1","(-6175,2750)","0","mstr_standard","I59";
;
CDS_LIB"mstr_standard"
BODY_TYPE"PLUMBING"
HDL_TAP"TRUE";
"B \NAC \NWC"6;
"S \NAC"
BN"6"84;
%"TAP"
"1","(-6175,2800)","0","mstr_standard","I60";
;
CDS_LIB"mstr_standard"
BODY_TYPE"PLUMBING"
HDL_TAP"TRUE";
"B \NAC \NWC"6;
"S \NAC"
BN"7"85;
%"TAP"
"1","(-6175,2850)","0","mstr_standard","I61";
;
CDS_LIB"mstr_standard"
BODY_TYPE"PLUMBING"
HDL_TAP"TRUE";
"B \NAC \NWC"6;
"S \NAC"
BN"8"86;
%"TAP"
"1","(-6175,2900)","0","mstr_standard","I62";
;
CDS_LIB"mstr_standard"
BODY_TYPE"PLUMBING"
HDL_TAP"TRUE";
"B \NAC \NWC"6;
"S \NAC"
BN"9"87;
%"TAP"
"1","(-6175,2950)","0","mstr_standard","I63";
;
CDS_LIB"mstr_standard"
BODY_TYPE"PLUMBING"
HDL_TAP"TRUE";
"B \NAC \NWC"6;
"S \NAC"
BN"10"88;
%"TAP"
"1","(-6175,3000)","0","mstr_standard","I64";
;
CDS_LIB"mstr_standard"
BODY_TYPE"PLUMBING"
HDL_TAP"TRUE";
"B \NAC \NWC"6;
"S \NAC"
BN"11"89;
%"TAP"
"1","(-6175,3100)","0","mstr_standard","I65";
;
CDS_LIB"mstr_standard"
BODY_TYPE"PLUMBING"
HDL_TAP"TRUE";
"B \NAC \NWC"6;
"S \NAC"
BN"13"91;
%"TAP"
"1","(-6175,3050)","0","mstr_standard","I66";
;
CDS_LIB"mstr_standard"
BODY_TYPE"PLUMBING"
HDL_TAP"TRUE";
"B \NAC \NWC"6;
"S \NAC"
BN"12"90;
%"TAP"
"1","(-6175,3200)","0","mstr_standard","I67";
;
CDS_LIB"mstr_standard"
BODY_TYPE"PLUMBING"
HDL_TAP"TRUE";
"B \NAC \NWC"6;
"S \NAC"
BN"15"93;
%"TAP"
"1","(-6175,3150)","0","mstr_standard","I68";
;
CDS_LIB"mstr_standard"
BODY_TYPE"PLUMBING"
HDL_TAP"TRUE";
"B \NAC \NWC"6;
"S \NAC"
BN"14"92;
%"TAP"
"1","(-6175,3250)","0","mstr_standard","I69";
;
CDS_LIB"mstr_standard"
BODY_TYPE"PLUMBING"
HDL_TAP"TRUE";
"B \NAC \NWC"6;
"S \NAC"
BN"16"94;
%"TAP"
"1","(-6175,3350)","0","mstr_standard","I70";
;
CDS_LIB"mstr_standard"
BODY_TYPE"PLUMBING"
HDL_TAP"TRUE";
"B \NAC \NWC"6;
"S \NAC"
BN"18"96;
%"TAP"
"1","(-6175,3400)","0","mstr_standard","I71";
;
CDS_LIB"mstr_standard"
BODY_TYPE"PLUMBING"
HDL_TAP"TRUE";
"B \NAC \NWC"6;
"S \NAC"
BN"19"97;
%"TAP"
"1","(-6175,3300)","0","mstr_standard","I72";
;
CDS_LIB"mstr_standard"
BODY_TYPE"PLUMBING"
HDL_TAP"TRUE";
"B \NAC \NWC"6;
"S \NAC"
BN"17"95;
%"TAP"
"1","(-6175,3500)","0","mstr_standard","I73";
;
CDS_LIB"mstr_standard"
BODY_TYPE"PLUMBING"
HDL_TAP"TRUE";
"B \NAC \NWC"6;
"S \NAC"
BN"21"99;
%"TAP"
"1","(-6175,3450)","0","mstr_standard","I74";
;
CDS_LIB"mstr_standard"
BODY_TYPE"PLUMBING"
HDL_TAP"TRUE";
"B \NAC \NWC"6;
"S \NAC"
BN"20"98;
%"TAP"
"1","(-6175,3550)","0","mstr_standard","I75";
;
CDS_LIB"mstr_standard"
BODY_TYPE"PLUMBING"
HDL_TAP"TRUE";
"B \NAC \NWC"6;
"S \NAC"
BN"22"100;
%"TAP"
"1","(-6175,3650)","0","mstr_standard","I76";
;
CDS_LIB"mstr_standard"
BODY_TYPE"PLUMBING"
HDL_TAP"TRUE";
"B \NAC \NWC"6;
"S \NAC"
BN"24"102;
%"TAP"
"1","(-6175,3600)","0","mstr_standard","I77";
;
CDS_LIB"mstr_standard"
BODY_TYPE"PLUMBING"
HDL_TAP"TRUE";
"B \NAC \NWC"6;
"S \NAC"
BN"23"101;
%"TAP"
"1","(-6175,3750)","0","mstr_standard","I78";
;
CDS_LIB"mstr_standard"
BODY_TYPE"PLUMBING"
HDL_TAP"TRUE";
"B \NAC \NWC"6;
"S \NAC"
BN"26"104;
%"TAP"
"1","(-6175,3700)","0","mstr_standard","I79";
;
CDS_LIB"mstr_standard"
BODY_TYPE"PLUMBING"
HDL_TAP"TRUE";
"B \NAC \NWC"6;
"S \NAC"
BN"25"103;
%"TAP"
"1","(-6175,3800)","0","mstr_standard","I80";
;
CDS_LIB"mstr_standard"
BODY_TYPE"PLUMBING"
HDL_TAP"TRUE";
"B \NAC \NWC"6;
"S \NAC"
BN"27"105;
%"TAP"
"1","(-6175,3900)","0","mstr_standard","I81";
;
CDS_LIB"mstr_standard"
BODY_TYPE"PLUMBING"
HDL_TAP"TRUE";
"B \NAC \NWC"6;
"S \NAC"
BN"29"107;
%"TAP"
"1","(-6175,3850)","0","mstr_standard","I82";
;
CDS_LIB"mstr_standard"
BODY_TYPE"PLUMBING"
HDL_TAP"TRUE";
"B \NAC \NWC"6;
"S \NAC"
BN"28"106;
%"TAP"
"1","(-6175,3950)","0","mstr_standard","I83";
;
CDS_LIB"mstr_standard"
BODY_TYPE"PLUMBING"
HDL_TAP"TRUE";
"B \NAC \NWC"6;
"S \NAC"
BN"30"108;
%"TAP"
"1","(-6175,4000)","0","mstr_standard","I84";
;
CDS_LIB"mstr_standard"
BODY_TYPE"PLUMBING"
HDL_TAP"TRUE";
"B \NAC \NWC"6;
"S \NAC"
BN"31"109;
%"TAP"
"1","(-6175,4150)","0","mstr_standard","I85";
;
CDS_LIB"mstr_standard"
BODY_TYPE"PLUMBING"
HDL_TAP"TRUE";
"B \NAC \NWC"5;
"S \NAC"
BN"1"111;
%"TAP"
"1","(-6175,4100)","0","mstr_standard","I86";
;
CDS_LIB"mstr_standard"
BODY_TYPE"PLUMBING"
HDL_TAP"TRUE";
"B \NAC \NWC"5;
"S \NAC"
BN"0"110;
%"TAP"
"1","(-6175,4200)","0","mstr_standard","I95";
;
CDS_LIB"mstr_standard"
BODY_TYPE"PLUMBING"
HDL_TAP"TRUE";
"B \NAC \NWC"5;
"S \NAC"
BN"2"112;
%"TAP"
"1","(-6175,4250)","0","mstr_standard","I96";
;
CDS_LIB"mstr_standard"
BODY_TYPE"PLUMBING"
HDL_TAP"TRUE";
"B \NAC \NWC"5;
"S \NAC"
BN"3"113;
%"TAP"
"1","(-6175,4300)","0","mstr_standard","I97";
;
CDS_LIB"mstr_standard"
BODY_TYPE"PLUMBING"
HDL_TAP"TRUE";
"B \NAC \NWC"5;
"S \NAC"
BN"4"114;
%"TAP"
"1","(-6175,4400)","0","mstr_standard","I98";
;
CDS_LIB"mstr_standard"
BODY_TYPE"PLUMBING"
HDL_TAP"TRUE";
"B \NAC \NWC"5;
"S \NAC"
BN"6"116;
%"TAP"
"1","(-6175,4350)","0","mstr_standard","I99";
;
CDS_LIB"mstr_standard"
BODY_TYPE"PLUMBING"
HDL_TAP"TRUE";
"B \NAC \NWC"5;
"S \NAC"
BN"5"115;
END.
